# TIMECARD (Time Appliance Project (Time Card)) — schematic netlist excerpt (pin names and nets, part order shuffled) for the footprints in the layout excerpt that follows; sources: Cadence DE-HDL packaged netlist, KiCad conversion of R4006-B0001-02_R01.brd

U33  IS32FL3207_QWLA3_TR_QFN29  IS32FL3207-QWLA3-TR  pkg QFN29_197_P0197_TR115SQ_V1  page 26
  \sdb*\  = RGB_LED_SHUTDOWN_N
  AD  = UNNAMED_14_IS32FL3207QWLA3TRQFN
  VCC  = XP3R3V_FPGA
  GND_1  = SG
  ISET  = UNNAMED_14_IS32FL3207QWLA3TRQ_1
  SDA  = R_RGB_LED_I2C_SDA
  SCL  = R_RGB_LED_I2C_SCL
  OUT1  = SMA1_LED_GREEN_N
  OUT2  = SMA1_LED_RED_N
  OUT3  = SMA1_LED_BLUE_N
  GND_2  = SG
  OUT4  = SMA2_LED_GREEN_N
  OUT5  = SMA2_LED_RED_N
  OUT6  = SMA2_LED_BLUE_N
  OUT7  = SMA3_LED_GREEN_N
  OUT8  = SMA3_LED_RED_N
  OUT9  = SMA3_LED_BLUE_N
  GND_3  = SG
  OUT10  = SMA4_LED_GREEN_N
  OUT11  = SMA4_LED_RED_N
  OUT12  = SMA4_LED_BLUE_N
  OUT13  = GPS_SMA_LED_GREEN_N
  OUT14  = GPS_SMA_LED_RED_N
  OUT15  = GPS_SMA_LED_BLUE_N
  GND_4  = SG
  OUT16  = NC
  OUT17  = NC
  OUT18  = NC
  THRM_PAD  = SG

(kicad_pcb
	(version 20260206)
	(generator "pcbnew")
	(generator_version "10.0")
	(general
		(thickness 1.6)
		(legacy_teardrops no)
	)
	(paper "A4")
	(title_block
		(title "timecard-production-celestica-r4006 — R4006-B0001-02_R01.brd")
		(comment 1 "Time Appliance Project (Time Card) / footprint 590 of 1113 (U33), pads 1-29 of 29")
	)
	(layers
		(0 "F.Cu" signal "TOP")
		(4 "In1.Cu" signal "L02_GND1")
		(6 "In2.Cu" signal "L03_SIG1")
		(8 "In3.Cu" signal "L04_GND2")
		(10 "In4.Cu" signal "L05_VCC1")
		(12 "In5.Cu" signal "L06_VCC2")
		(14 "In6.Cu" signal "L07_GND3")
		(16 "In7.Cu" signal "L08_SIG2")
		(18 "In8.Cu" signal "L09_GND4")
		(2 "B.Cu" signal "BOTTOM")
		(9 "F.Adhes" user "F.Adhesive")
		(11 "B.Adhes" user "B.Adhesive")
		(13 "F.Paste" user "Package Geometry/Pastemask Top")
		(15 "B.Paste" user "Package Geometry/Pastemask Bottom")
		(5 "F.SilkS" user "Ref Des/Silkscreen Top")
		(7 "B.SilkS" user "Ref Des/Silkscreen Bottom")
		(1 "F.Mask" user "Board Geometry/Soldermask Top")
		(3 "B.Mask" user "Board Geometry/Soldermask Bottom")
		(17 "Dwgs.User" user "User.Drawings")
		(19 "Cmts.User" user "User.Comments")
		(21 "Eco1.User" user "User.Eco1")
		(23 "Eco2.User" user "User.Eco2")
		(25 "Edge.Cuts" user "Board Geometry/Outline")
		(27 "Margin" user)
		(31 "F.CrtYd" user "Package Geometry/Place Bound Top")
		(29 "B.CrtYd" user "Package Geometry/Place Bound Bottom")
		(35 "F.Fab" user "Ref Des/Assembly Top")
		(33 "B.Fab" user "Ref Des/Assembly Bottom")
	)
	(footprint ""
		(layer "F.Cu")
		(at 105.2576 -101.3968 180)
		(property "Reference" "U33"
			(at -1.5494 5.11683 0)
			(unlocked yes)
			(layer "F.SilkS")
			(effects
				(font
					(size 0.7874 0.5842)
					(thickness 0.1524)
				)
			)
		)
		(property "Value" ""
			(at 0 0 180)
			(layer "F.Fab")
			(effects
				(font
					(size 1.27 1.27)
				)
			)
		)
		(property "Device Type" "IS32FL3207_QWLA3_TR_QFN29-A223A"
			(at 0 5.031486 180)
			(unlocked yes)
			(layer "F.Fab")
			(hide yes)
			(effects
				(font
					(size 0.7874 0.5842)
					(thickness 0.1524)
				)
			)
		)
		(property "User Part Number" "PARTNUM*"
			(at 0 6.225286 180)
			(unlocked yes)
			(layer "Cmts.User")
			(hide yes)
			(effects
				(font
					(size 0.7874 0.5842)
					(thickness 0.1524)
				)
			)
		)
		(duplicate_pad_numbers_are_jumpers no)
		(pad "1" smd rect
			(at -2.45364 -1.500124 180)
			(size 1.1684 0.3048)
			(layers "F.Cu" "F.Mask" "F.Paste")
			(net "RGB_LED_SHUTDOWN_N")
		)
		(pad "2" smd rect
			(at -2.41554 -0.999998 180)
			(size 1.2446 0.3048)
			(layers "F.Cu" "F.Mask" "F.Paste")
			(net "UNNAMED_14_IS32FL3207QWLA3TRQFN")
		)
		(pad "3" smd rect
			(at -2.41554 -0.500126 180)
			(size 1.2446 0.3048)
			(layers "F.Cu" "F.Mask" "F.Paste")
			(net "XP3R3V_FPGA")
		)
		(pad "4" smd rect
			(at -2.41554 0 180)
			(size 1.2446 0.3048)
			(layers "F.Cu" "F.Mask" "F.Paste")
			(net "SG")
		)
		(pad "5" smd rect
			(at -2.41554 0.500126 180)
			(size 1.2446 0.3048)
			(layers "F.Cu" "F.Mask" "F.Paste")
			(net "UNNAMED_14_IS32FL3207QWLA3TRQ_1")
		)
		(pad "6" smd rect
			(at -2.41554 0.999998 180)
			(size 1.2446 0.3048)
			(layers "F.Cu" "F.Mask" "F.Paste")
			(net "R_RGB_LED_I2C_SDA")
		)
		(pad "7" smd rect
			(at -2.45364 1.500124 180)
			(size 1.1684 0.3048)
			(layers "F.Cu" "F.Mask" "F.Paste")
			(net "R_RGB_LED_I2C_SCL")
		)
		(pad "8" smd rect
			(at -1.500124 2.45364 180)
			(size 0.3048 1.1684)
			(layers "F.Cu" "F.Mask" "F.Paste")
			(net "SMA1_LED_GREEN_N")
		)
		(pad "9" smd rect
			(at -0.999998 2.41554 180)
			(size 0.3048 1.2446)
			(layers "F.Cu" "F.Mask" "F.Paste")
			(net "SMA1_LED_RED_N")
		)
		(pad "10" smd rect
			(at -0.500126 2.41554 180)
			(size 0.3048 1.2446)
			(layers "F.Cu" "F.Mask" "F.Paste")
			(net "SMA1_LED_BLUE_N")
		)
		(pad "11" smd rect
			(at 0 2.41554 180)
			(size 0.3048 1.2446)
			(layers "F.Cu" "F.Mask" "F.Paste")
			(net "SG")
		)
		(pad "12" smd rect
			(at 0.500126 2.41554 180)
			(size 0.3048 1.2446)
			(layers "F.Cu" "F.Mask" "F.Paste")
			(net "SMA2_LED_GREEN_N")
		)
		(pad "13" smd rect
			(at 0.999998 2.41554 180)
			(size 0.3048 1.2446)
			(layers "F.Cu" "F.Mask" "F.Paste")
			(net "SMA2_LED_RED_N")
		)
		(pad "14" smd rect
			(at 1.500124 2.45364 180)
			(size 0.3048 1.1684)
			(layers "F.Cu" "F.Mask" "F.Paste")
			(net "SMA2_LED_BLUE_N")
		)
		(pad "15" smd rect
			(at 2.45364 1.500124 180)
			(size 1.1684 0.3048)
			(layers "F.Cu" "F.Mask" "F.Paste")
			(net "SMA3_LED_GREEN_N")
		)
		(pad "16" smd rect
			(at 2.41554 0.999998 180)
			(size 1.2446 0.3048)
			(layers "F.Cu" "F.Mask" "F.Paste")
			(net "SMA3_LED_RED_N")
		)
		(pad "17" smd rect
			(at 2.41554 0.500126 180)
			(size 1.2446 0.3048)
			(layers "F.Cu" "F.Mask" "F.Paste")
			(net "SMA3_LED_BLUE_N")
		)
		(pad "18" smd rect
			(at 2.41554 0 180)
			(size 1.2446 0.3048)
			(layers "F.Cu" "F.Mask" "F.Paste")
			(net "SG")
		)
		(pad "19" smd rect
			(at 2.41554 -0.500126 180)
			(size 1.2446 0.3048)
			(layers "F.Cu" "F.Mask" "F.Paste")
			(net "SMA4_LED_GREEN_N")
		)
		(pad "20" smd rect
			(at 2.41554 -0.999998 180)
			(size 1.2446 0.3048)
			(layers "F.Cu" "F.Mask" "F.Paste")
			(net "SMA4_LED_RED_N")
		)
		(pad "21" smd rect
			(at 2.45364 -1.500124 180)
			(size 1.1684 0.3048)
			(layers "F.Cu" "F.Mask" "F.Paste")
			(net "SMA4_LED_BLUE_N")
		)
		(pad "22" smd rect
			(at 1.500124 -2.45364 180)
			(size 0.3048 1.1684)
			(layers "F.Cu" "F.Mask" "F.Paste")
			(net "GPS_SMA_LED_GREEN_N")
		)
		(pad "23" smd rect
			(at 0.999998 -2.41554 180)
			(size 0.3048 1.2446)
			(layers "F.Cu" "F.Mask" "F.Paste")
			(net "GPS_SMA_LED_RED_N")
		)
		(pad "24" smd rect
			(at 0.500126 -2.41554 180)
			(size 0.3048 1.2446)
			(layers "F.Cu" "F.Mask" "F.Paste")
			(net "GPS_SMA_LED_BLUE_N")
		)
		(pad "25" smd rect
			(at 0 -2.41554 180)
			(size 0.3048 1.2446)
			(layers "F.Cu" "F.Mask" "F.Paste")
			(net "SG")
		)
		(pad "26" smd rect
			(at -0.500126 -2.41554 180)
			(size 0.3048 1.2446)
			(layers "F.Cu" "F.Mask" "F.Paste")
			(net "Net_785")
		)
		(pad "27" smd rect
			(at -0.999998 -2.41554 180)
			(size 0.3048 1.2446)
			(layers "F.Cu" "F.Mask" "F.Paste")
			(net "Net_784")
		)
		(pad "28" smd rect
			(at -1.500124 -2.45364 180)
			(size 0.3048 1.1684)
			(layers "F.Cu" "F.Mask" "F.Paste")
			(net "Net_783")
		)
		(pad "29" smd rect
			(at 0 0 180)
			(size 2.921 2.921)
			(layers "F.Cu" "F.Mask" "F.Paste")
			(net "SG")
		)
	)
)
